# S9S_MB_2U (Grand Teton) — schematic netlist excerpt (pin names and nets, part order shuffled) for the footprints in the layout excerpt that follows; sources: Cadence DE-HDL packaged netlist, KiCad conversion of 03242023_DA0F0TMBIJ0_F0T_Motherboard_J_brd_V01_OCP.brd

R3902  Q_RES  49.9 1% CHIP  pkg 0402LF  page 109 : A = I3C_SPD_DDREFGH_CPU1_LVC1_SCL_3 ; B = I3C_SPD_DDREFGH_CPU1_LVC1_SCL
PR4251  Q_RES  0 5% CHIP  pkg 0402LF  page 296 : A = NC_PVCCD_HV_CPU1_ACSP2 ; B = GND

(kicad_pcb
	(version 20260206)
	(generator "pcbnew")
	(generator_version "10.0")
	(general
		(thickness 1.6)
		(legacy_teardrops no)
	)
	(paper "A4")
	(title_block
		(title "03242023_DA0F0TMBIJ0_F0T_Motherboard_J_brd_V01_OCP.brd")
		(comment 1 "Grand Teton / footprints 4693-4694 of 6105")
	)
	(layers
		(0 "F.Cu" signal "TOP")
		(4 "In1.Cu" signal "GND")
		(6 "In2.Cu" signal "IN1")
		(8 "In3.Cu" signal "GND1")
		(10 "In4.Cu" signal "IN2")
		(12 "In5.Cu" signal "GND2")
		(14 "In6.Cu" signal "IN3")
		(16 "In7.Cu" signal "GND3")
		(18 "In8.Cu" signal "VCC")
		(20 "In9.Cu" signal "VCC1")
		(22 "In10.Cu" signal "GND4")
		(24 "In11.Cu" signal "IN4")
		(26 "In12.Cu" signal "GND5")
		(28 "In13.Cu" signal "IN5")
		(30 "In14.Cu" signal "GND6")
		(32 "In15.Cu" signal "IN6")
		(34 "In16.Cu" signal "GND7")
		(2 "B.Cu" signal "BOTTOM")
		(9 "F.Adhes" user "F.Adhesive")
		(11 "B.Adhes" user "B.Adhesive")
		(13 "F.Paste" user "Package Geometry/Pastemask Top")
		(15 "B.Paste" user "Package Geometry/Pastemask Bottom")
		(5 "F.SilkS" user "Ref Des/Silkscreen Top")
		(7 "B.SilkS" user "Ref Des/Silkscreen Bottom")
		(1 "F.Mask" user "Board Geometry/Soldermask Top")
		(3 "B.Mask" user "Board Geometry/Soldermask Bottom")
		(17 "Dwgs.User" user "User.Drawings")
		(19 "Cmts.User" user "User.Comments")
		(21 "Eco1.User" user "User.Eco1")
		(23 "Eco2.User" user "User.Eco2")
		(25 "Edge.Cuts" user "Board Geometry/Outline")
		(27 "Margin" user)
		(31 "F.CrtYd" user "Package Geometry/Place Bound Top")
		(29 "B.CrtYd" user "Package Geometry/Place Bound Bottom")
		(35 "F.Fab" user "Ref Des/Assembly Top")
		(33 "B.Fab" user "Ref Des/Assembly Bottom")
	)
	(footprint ""
		(layer "B.Cu")
		(at 173.91507 -317.48984 90)
		(property "Reference" "R3902"
			(at 0 0 90)
			(layer "B.SilkS")
			(hide yes)
			(effects
				(font
					(size 1.27 1.27)
				)
				(justify mirror)
			)
		)
		(property "Value" ""
			(at 0 0 90)
			(layer "B.Fab")
			(effects
				(font
					(size 1.27 1.27)
				)
				(justify mirror)
			)
		)
		(duplicate_pad_numbers_are_jumpers no)
		(fp_line
			(start 0.7874 -0.4064)
			(end -0.7874 -0.4064)
			(stroke
				(width 0.1524)
				(type default)
			)
			(layer "B.SilkS")
		)
		(fp_line
			(start -0.7874 -0.4064)
			(end -0.7874 0.4064)
			(stroke
				(width 0.1524)
				(type default)
			)
			(layer "B.SilkS")
		)
		(fp_line
			(start 0.7874 0.4064)
			(end 0.7874 -0.4064)
			(stroke
				(width 0.1524)
				(type default)
			)
			(layer "B.SilkS")
		)
		(fp_line
			(start -0.7874 0.4064)
			(end 0.7874 0.4064)
			(stroke
				(width 0.1524)
				(type default)
			)
			(layer "B.SilkS")
		)
		(fp_line
			(start 0.67945 -0.305054)
			(end 0.12065 -0.305054)
			(stroke
				(width 0.1)
				(type default)
			)
			(layer "B.Fab")
		)
		(fp_line
			(start 0.12065 -0.305054)
			(end 0.12065 -0.2794)
			(stroke
				(width 0.1)
				(type default)
			)
			(layer "B.Fab")
		)
		(fp_line
			(start -0.12065 -0.3048)
			(end -0.67945 -0.3048)
			(stroke
				(width 0.1)
				(type default)
			)
			(layer "B.Fab")
		)
		(fp_line
			(start -0.67945 -0.3048)
			(end -0.67945 0.3048)
			(stroke
				(width 0.1)
				(type default)
			)
			(layer "B.Fab")
		)
		(fp_line
			(start 0.12065 -0.2794)
			(end -0.12065 -0.2794)
			(stroke
				(width 0.1)
				(type default)
			)
			(layer "B.Fab")
		)
		(fp_line
			(start -0.12065 -0.2794)
			(end -0.12065 -0.3048)
			(stroke
				(width 0.1)
				(type default)
			)
			(layer "B.Fab")
		)
		(fp_line
			(start 0.12065 0.2794)
			(end 0.12065 0.3048)
			(stroke
				(width 0.1)
				(type default)
			)
			(layer "B.Fab")
		)
		(fp_line
			(start -0.120396 0.2794)
			(end 0.12065 0.2794)
			(stroke
				(width 0.1)
				(type default)
			)
			(layer "B.Fab")
		)
		(fp_line
			(start 0.67945 0.3048)
			(end 0.67945 -0.305054)
			(stroke
				(width 0.1)
				(type default)
			)
			(layer "B.Fab")
		)
		(fp_line
			(start 0.12065 0.3048)
			(end 0.67945 0.3048)
			(stroke
				(width 0.1)
				(type default)
			)
			(layer "B.Fab")
		)
		(fp_line
			(start -0.120396 0.3048)
			(end -0.120396 0.2794)
			(stroke
				(width 0.1)
				(type default)
			)
			(layer "B.Fab")
		)
		(fp_line
			(start -0.67945 0.3048)
			(end -0.120396 0.3048)
			(stroke
				(width 0.1)
				(type default)
			)
			(layer "B.Fab")
		)
		(pad "1" smd circle
			(at 0.40005 0 270)
			(size 0 0)
			(layers "B.Cu" "B.Mask" "B.Paste")
			(net "I3C_SPD_DDREFGH_CPU1_LVC1_SCL_3")
		)
		(pad "2" smd circle
			(at -0.40005 0 270)
			(size 0 0)
			(layers "B.Cu" "B.Mask" "B.Paste")
			(net "I3C_SPD_DDREFGH_CPU1_LVC1_SCL")
		)
	)
	(footprint ""
		(layer "B.Cu")
		(at 24.895302 -163.105846 180)
		(property "Reference" "PR4251"
			(at 0 0 0)
			(layer "B.SilkS")
			(hide yes)
			(effects
				(font
					(size 1.27 1.27)
				)
				(justify mirror)
			)
		)
		(property "Value" ""
			(at 0 0 0)
			(layer "B.Fab")
			(effects
				(font
					(size 1.27 1.27)
				)
				(justify mirror)
			)
		)
		(duplicate_pad_numbers_are_jumpers no)
		(fp_line
			(start 0.7874 0.4064)
			(end 0.7874 -0.4064)
			(stroke
				(width 0.1524)
				(type default)
			)
			(layer "B.SilkS")
		)
		(fp_line
			(start 0.7874 -0.4064)
			(end -0.7874 -0.4064)
			(stroke
				(width 0.1524)
				(type default)
			)
			(layer "B.SilkS")
		)
		(fp_line
			(start -0.7874 0.4064)
			(end 0.7874 0.4064)
			(stroke
				(width 0.1524)
				(type default)
			)
			(layer "B.SilkS")
		)
		(fp_line
			(start -0.7874 -0.4064)
			(end -0.7874 0.4064)
			(stroke
				(width 0.1524)
				(type default)
			)
			(layer "B.SilkS")
		)
		(fp_line
			(start 0.67945 0.3048)
			(end 0.67945 -0.305054)
			(stroke
				(width 0.1)
				(type default)
			)
			(layer "B.Fab")
		)
		(fp_line
			(start 0.67945 -0.305054)
			(end 0.12065 -0.305054)
			(stroke
				(width 0.1)
				(type default)
			)
			(layer "B.Fab")
		)
		(fp_line
			(start 0.12065 0.3048)
			(end 0.67945 0.3048)
			(stroke
				(width 0.1)
				(type default)
			)
			(layer "B.Fab")
		)
		(fp_line
			(start 0.12065 0.2794)
			(end 0.12065 0.3048)
			(stroke
				(width 0.1)
				(type default)
			)
			(layer "B.Fab")
		)
		(fp_line
			(start 0.12065 -0.2794)
			(end -0.12065 -0.2794)
			(stroke
				(width 0.1)
				(type default)
			)
			(layer "B.Fab")
		)
		(fp_line
			(start 0.12065 -0.305054)
			(end 0.12065 -0.2794)
			(stroke
				(width 0.1)
				(type default)
			)
			(layer "B.Fab")
		)
		(fp_line
			(start -0.120396 0.3048)
			(end -0.120396 0.2794)
			(stroke
				(width 0.1)
				(type default)
			)
			(layer "B.Fab")
		)
		(fp_line
			(start -0.120396 0.2794)
			(end 0.12065 0.2794)
			(stroke
				(width 0.1)
				(type default)
			)
			(layer "B.Fab")
		)
		(fp_line
			(start -0.12065 -0.2794)
			(end -0.12065 -0.3048)
			(stroke
				(width 0.1)
				(type default)
			)
			(layer "B.Fab")
		)
		(fp_line
			(start -0.12065 -0.3048)
			(end -0.67945 -0.3048)
			(stroke
				(width 0.1)
				(type default)
			)
			(layer "B.Fab")
		)
		(fp_line
			(start -0.67945 0.3048)
			(end -0.120396 0.3048)
			(stroke
				(width 0.1)
				(type default)
			)
			(layer "B.Fab")
		)
		(fp_line
			(start -0.67945 -0.3048)
			(end -0.67945 0.3048)
			(stroke
				(width 0.1)
				(type default)
			)
			(layer "B.Fab")
		)
		(pad "1" smd circle
			(at 0.40005 0)
			(size 0 0)
			(layers "B.Cu" "B.Mask" "B.Paste")
			(net "NC_PVCCD_HV_CPU1_ACSP2")
		)
		(pad "2" smd circle
			(at -0.40005 0)
			(size 0 0)
			(layers "B.Cu" "B.Mask" "B.Paste")
			(net "GND")
		)
	)
)
